# T6G (Grand Teton) — schematic netlist excerpt (pin names and nets, part order shuffled) for the footprints in the layout excerpt that follows; sources: Cadence DE-HDL packaged netlist, KiCad conversion of 04192023_DAF0TMB3IC0_F0TG_MB_C_brd_V02_OCP.brd

PC168  Q_CAP  560PF 50V 10% EMPTY  pkg C0402  page 208 : A = SW_PVDD11_S3_P0_SW2 ; B = SW_PVDD11_S3_P0_SW2_RC
R3872  Q_RES  0 5% EMPTY  pkg 0402LF  page 135 : A = P12V_OCP_IMON_1 ; B = P12V_OCP_SFF_ISENSE_MPS_TIC

(kicad_pcb
	(version 20260206)
	(generator "pcbnew")
	(generator_version "10.0")
	(general
		(thickness 1.6)
		(legacy_teardrops no)
	)
	(paper "A4")
	(title_block
		(title "04192023_DAF0TMB3IC0_F0TG_MB_C_brd_V02_OCP.brd")
		(comment 1 "Grand Teton / footprints 1794-1795 of 8354")
	)
	(layers
		(0 "F.Cu" signal "TOP")
		(4 "In1.Cu" signal "GND")
		(6 "In2.Cu" signal "IN1")
		(8 "In3.Cu" signal "GND1")
		(10 "In4.Cu" signal "IN2")
		(12 "In5.Cu" signal "GND2")
		(14 "In6.Cu" signal "IN3")
		(16 "In7.Cu" signal "GND3")
		(18 "In8.Cu" signal "VCC")
		(20 "In9.Cu" signal "VCC1")
		(22 "In10.Cu" signal "GND4")
		(24 "In11.Cu" signal "IN4")
		(26 "In12.Cu" signal "GND5")
		(28 "In13.Cu" signal "IN5")
		(30 "In14.Cu" signal "GND6")
		(32 "In15.Cu" signal "IN6")
		(34 "In16.Cu" signal "GND7")
		(2 "B.Cu" signal "BOTTOM")
		(9 "F.Adhes" user "F.Adhesive")
		(11 "B.Adhes" user "B.Adhesive")
		(13 "F.Paste" user "Package Geometry/Pastemask Top")
		(15 "B.Paste" user "Package Geometry/Pastemask Bottom")
		(5 "F.SilkS" user "Ref Des/Silkscreen Top")
		(7 "B.SilkS" user "Ref Des/Silkscreen Bottom")
		(1 "F.Mask" user "Board Geometry/Soldermask Top")
		(3 "B.Mask" user "Board Geometry/Soldermask Bottom")
		(17 "Dwgs.User" user "User.Drawings")
		(19 "Cmts.User" user "User.Comments")
		(21 "Eco1.User" user "User.Eco1")
		(23 "Eco2.User" user "User.Eco2")
		(25 "Edge.Cuts" user "Board Geometry/Outline")
		(27 "Margin" user)
		(31 "F.CrtYd" user "Package Geometry/Place Bound Top")
		(29 "B.CrtYd" user "Package Geometry/Place Bound Bottom")
		(35 "F.Fab" user "Ref Des/Assembly Top")
		(33 "B.Fab" user "Ref Des/Assembly Bottom")
	)
	(footprint ""
		(layer "F.Cu")
		(at 436.224172 -32.173418 90)
		(property "Reference" "R3872"
			(at 0 0 90)
			(layer "F.SilkS")
			(hide yes)
			(effects
				(font
					(size 1.27 1.27)
				)
			)
		)
		(property "Value" ""
			(at 0 0 90)
			(layer "F.Fab")
			(effects
				(font
					(size 1.27 1.27)
				)
			)
		)
		(duplicate_pad_numbers_are_jumpers no)
		(fp_line
			(start 0.7874 -0.4064)
			(end 0.7874 0.4064)
			(stroke
				(width 0.1524)
				(type default)
			)
			(layer "F.SilkS")
		)
		(fp_line
			(start -0.7874 -0.4064)
			(end 0.7874 -0.4064)
			(stroke
				(width 0.1524)
				(type default)
			)
			(layer "F.SilkS")
		)
		(fp_line
			(start 0.7874 0.4064)
			(end -0.7874 0.4064)
			(stroke
				(width 0.1524)
				(type default)
			)
			(layer "F.SilkS")
		)
		(fp_line
			(start -0.7874 0.4064)
			(end -0.7874 -0.4064)
			(stroke
				(width 0.1524)
				(type default)
			)
			(layer "F.SilkS")
		)
		(fp_line
			(start -0.12065 -0.305054)
			(end -0.12065 -0.2794)
			(stroke
				(width 0.1)
				(type default)
			)
			(layer "F.Fab")
		)
		(fp_line
			(start -0.67945 -0.305054)
			(end -0.12065 -0.305054)
			(stroke
				(width 0.1)
				(type default)
			)
			(layer "F.Fab")
		)
		(fp_line
			(start 0.67945 -0.3048)
			(end 0.67945 0.3048)
			(stroke
				(width 0.1)
				(type default)
			)
			(layer "F.Fab")
		)
		(fp_line
			(start 0.12065 -0.3048)
			(end 0.67945 -0.3048)
			(stroke
				(width 0.1)
				(type default)
			)
			(layer "F.Fab")
		)
		(fp_line
			(start 0.12065 -0.2794)
			(end 0.12065 -0.3048)
			(stroke
				(width 0.1)
				(type default)
			)
			(layer "F.Fab")
		)
		(fp_line
			(start -0.12065 -0.2794)
			(end 0.12065 -0.2794)
			(stroke
				(width 0.1)
				(type default)
			)
			(layer "F.Fab")
		)
		(fp_line
			(start 0.120396 0.2794)
			(end -0.12065 0.2794)
			(stroke
				(width 0.1)
				(type default)
			)
			(layer "F.Fab")
		)
		(fp_line
			(start -0.12065 0.2794)
			(end -0.12065 0.3048)
			(stroke
				(width 0.1)
				(type default)
			)
			(layer "F.Fab")
		)
		(fp_line
			(start 0.67945 0.3048)
			(end 0.120396 0.3048)
			(stroke
				(width 0.1)
				(type default)
			)
			(layer "F.Fab")
		)
		(fp_line
			(start 0.120396 0.3048)
			(end 0.120396 0.2794)
			(stroke
				(width 0.1)
				(type default)
			)
			(layer "F.Fab")
		)
		(fp_line
			(start -0.12065 0.3048)
			(end -0.67945 0.3048)
			(stroke
				(width 0.1)
				(type default)
			)
			(layer "F.Fab")
		)
		(fp_line
			(start -0.67945 0.3048)
			(end -0.67945 -0.305054)
			(stroke
				(width 0.1)
				(type default)
			)
			(layer "F.Fab")
		)
		(pad "1" smd circle
			(at -0.40005 0 90)
			(size 0 0)
			(layers "F.Cu" "F.Mask" "F.Paste")
			(net "P12V_OCP_IMON_1")
		)
		(pad "2" smd circle
			(at 0.40005 0 90)
			(size 0 0)
			(layers "F.Cu" "F.Mask" "F.Paste")
			(net "P12V_OCP_SFF_ISENSE_MPS_TIC")
		)
	)
	(footprint ""
		(layer "F.Cu")
		(at 428.276766 -348.135956 180)
		(property "Reference" "PC168"
			(at 0 0 180)
			(layer "F.SilkS")
			(hide yes)
			(effects
				(font
					(size 1.27 1.27)
				)
			)
		)
		(property "Value" ""
			(at 0 0 180)
			(layer "F.Fab")
			(effects
				(font
					(size 1.27 1.27)
				)
			)
		)
		(duplicate_pad_numbers_are_jumpers no)
		(fp_line
			(start 0.7874 0.4064)
			(end -0.7874 0.4064)
			(stroke
				(width 0.1524)
				(type default)
			)
			(layer "F.SilkS")
		)
		(fp_line
			(start 0.7874 -0.4064)
			(end 0.7874 0.4064)
			(stroke
				(width 0.1524)
				(type default)
			)
			(layer "F.SilkS")
		)
		(fp_line
			(start -0.7874 0.4064)
			(end -0.7874 -0.4064)
			(stroke
				(width 0.1524)
				(type default)
			)
			(layer "F.SilkS")
		)
		(fp_line
			(start -0.7874 -0.4064)
			(end 0.7874 -0.4064)
			(stroke
				(width 0.1524)
				(type default)
			)
			(layer "F.SilkS")
		)
		(fp_line
			(start 0.67945 0.3048)
			(end 0.120396 0.3048)
			(stroke
				(width 0.1)
				(type default)
			)
			(layer "F.Fab")
		)
		(fp_line
			(start 0.67945 -0.3048)
			(end 0.67945 0.3048)
			(stroke
				(width 0.1)
				(type default)
			)
			(layer "F.Fab")
		)
		(fp_line
			(start 0.12065 -0.2794)
			(end 0.12065 -0.3048)
			(stroke
				(width 0.1)
				(type default)
			)
			(layer "F.Fab")
		)
		(fp_line
			(start 0.12065 -0.3048)
			(end 0.67945 -0.3048)
			(stroke
				(width 0.1)
				(type default)
			)
			(layer "F.Fab")
		)
		(fp_line
			(start 0.120396 0.3048)
			(end 0.120396 0.2794)
			(stroke
				(width 0.1)
				(type default)
			)
			(layer "F.Fab")
		)
		(fp_line
			(start 0.120396 0.2794)
			(end -0.12065 0.2794)
			(stroke
				(width 0.1)
				(type default)
			)
			(layer "F.Fab")
		)
		(fp_line
			(start -0.12065 0.3048)
			(end -0.67945 0.3048)
			(stroke
				(width 0.1)
				(type default)
			)
			(layer "F.Fab")
		)
		(fp_line
			(start -0.12065 0.2794)
			(end -0.12065 0.3048)
			(stroke
				(width 0.1)
				(type default)
			)
			(layer "F.Fab")
		)
		(fp_line
			(start -0.12065 -0.2794)
			(end 0.12065 -0.2794)
			(stroke
				(width 0.1)
				(type default)
			)
			(layer "F.Fab")
		)
		(fp_line
			(start -0.12065 -0.305054)
			(end -0.12065 -0.2794)
			(stroke
				(width 0.1)
				(type default)
			)
			(layer "F.Fab")
		)
		(fp_line
			(start -0.67945 0.3048)
			(end -0.67945 -0.305054)
			(stroke
				(width 0.1)
				(type default)
			)
			(layer "F.Fab")
		)
		(fp_line
			(start -0.67945 -0.305054)
			(end -0.12065 -0.305054)
			(stroke
				(width 0.1)
				(type default)
			)
			(layer "F.Fab")
		)
		(pad "1" smd circle
			(at -0.40005 0 180)
			(size 0 0)
			(layers "F.Cu" "F.Mask" "F.Paste")
			(net "SW_PVDD11_S3_P0_SW2")
		)
		(pad "2" smd circle
			(at 0.40005 0 180)
			(size 0 0)
			(layers "F.Cu" "F.Mask" "F.Paste")
			(net "SW_PVDD11_S3_P0_SW2_RC")
		)
	)
)
